(kicad_pcb
	(version 20260206)
	(generator "pcbnew")
	(generator_version "10.0")
	(general
		(thickness 1.6)
		(legacy_teardrops no)
	)
	(paper "A4")
	(title_block
		(title "04192023_DAF0TMB3IC0_F0TG_MB_C_brd_V02_OCP.brd")
		(comment 1 "Grand Teton / footprints 4728-4734 of 8354")
	)
	(layers
		(0 "F.Cu" signal "TOP")
		(4 "In1.Cu" signal "GND")
		(6 "In2.Cu" signal "IN1")
		(8 "In3.Cu" signal "GND1")
		(10 "In4.Cu" signal "IN2")
		(12 "In5.Cu" signal "GND2")
		(14 "In6.Cu" signal "IN3")
		(16 "In7.Cu" signal "GND3")
		(18 "In8.Cu" signal "VCC")
		(20 "In9.Cu" signal "VCC1")
		(22 "In10.Cu" signal "GND4")
		(24 "In11.Cu" signal "IN4")
		(26 "In12.Cu" signal "GND5")
		(28 "In13.Cu" signal "IN5")
		(30 "In14.Cu" signal "GND6")
		(32 "In15.Cu" signal "IN6")
		(34 "In16.Cu" signal "GND7")
		(2 "B.Cu" signal "BOTTOM")
		(9 "F.Adhes" user "F.Adhesive")
		(11 "B.Adhes" user "B.Adhesive")
		(13 "F.Paste" user "Package Geometry/Pastemask Top")
		(15 "B.Paste" user "Package Geometry/Pastemask Bottom")
		(5 "F.SilkS" user "Ref Des/Silkscreen Top")
		(7 "B.SilkS" user "Ref Des/Silkscreen Bottom")
		(1 "F.Mask" user "Board Geometry/Soldermask Top")
		(3 "B.Mask" user "Board Geometry/Soldermask Bottom")
		(17 "Dwgs.User" user "User.Drawings")
		(19 "Cmts.User" user "User.Comments")
		(21 "Eco1.User" user "User.Eco1")
		(23 "Eco2.User" user "User.Eco2")
		(25 "Edge.Cuts" user "Board Geometry/Outline")
		(27 "Margin" user)
		(31 "F.CrtYd" user "Package Geometry/Place Bound Top")
		(29 "B.CrtYd" user "Package Geometry/Place Bound Bottom")
		(35 "F.Fab" user "Ref Des/Assembly Top")
		(33 "B.Fab" user "Ref Des/Assembly Bottom")
	)
	(footprint ""
		(layer "F.Cu")
		(at 382.391158 -323.186552 90)
		(property "Reference" "R939"
			(at 0 0 90)
			(layer "F.SilkS")
			(hide yes)
			(effects
				(font
					(size 1.27 1.27)
				)
			)
		)
		(property "Value" ""
			(at 0 0 90)
			(layer "F.Fab")
			(effects
				(font
					(size 1.27 1.27)
				)
			)
		)
		(duplicate_pad_numbers_are_jumpers no)
		(fp_line
			(start 0.7874 -0.4064)
			(end 0.7874 0.4064)
			(stroke
				(width 0.1524)
				(type default)
			)
			(layer "F.SilkS")
		)
		(fp_line
			(start -0.7874 -0.4064)
			(end 0.7874 -0.4064)
			(stroke
				(width 0.1524)
				(type default)
			)
			(layer "F.SilkS")
		)
		(fp_line
			(start 0.7874 0.4064)
			(end -0.7874 0.4064)
			(stroke
				(width 0.1524)
				(type default)
			)
			(layer "F.SilkS")
		)
		(fp_line
			(start -0.7874 0.4064)
			(end -0.7874 -0.4064)
			(stroke
				(width 0.1524)
				(type default)
			)
			(layer "F.SilkS")
		)
		(fp_line
			(start -0.12065 -0.305054)
			(end -0.12065 -0.2794)
			(stroke
				(width 0.1)
				(type default)
			)
			(layer "F.Fab")
		)
		(fp_line
			(start -0.67945 -0.305054)
			(end -0.12065 -0.305054)
			(stroke
				(width 0.1)
				(type default)
			)
			(layer "F.Fab")
		)
		(fp_line
			(start 0.67945 -0.3048)
			(end 0.67945 0.3048)
			(stroke
				(width 0.1)
				(type default)
			)
			(layer "F.Fab")
		)
		(fp_line
			(start 0.12065 -0.3048)
			(end 0.67945 -0.3048)
			(stroke
				(width 0.1)
				(type default)
			)
			(layer "F.Fab")
		)
		(fp_line
			(start 0.12065 -0.2794)
			(end 0.12065 -0.3048)
			(stroke
				(width 0.1)
				(type default)
			)
			(layer "F.Fab")
		)
		(fp_line
			(start -0.12065 -0.2794)
			(end 0.12065 -0.2794)
			(stroke
				(width 0.1)
				(type default)
			)
			(layer "F.Fab")
		)
		(fp_line
			(start 0.120396 0.2794)
			(end -0.12065 0.2794)
			(stroke
				(width 0.1)
				(type default)
			)
			(layer "F.Fab")
		)
		(fp_line
			(start -0.12065 0.2794)
			(end -0.12065 0.3048)
			(stroke
				(width 0.1)
				(type default)
			)
			(layer "F.Fab")
		)
		(fp_line
			(start 0.67945 0.3048)
			(end 0.120396 0.3048)
			(stroke
				(width 0.1)
				(type default)
			)
			(layer "F.Fab")
		)
		(fp_line
			(start 0.120396 0.3048)
			(end 0.120396 0.2794)
			(stroke
				(width 0.1)
				(type default)
			)
			(layer "F.Fab")
		)
		(fp_line
			(start -0.12065 0.3048)
			(end -0.67945 0.3048)
			(stroke
				(width 0.1)
				(type default)
			)
			(layer "F.Fab")
		)
		(fp_line
			(start -0.67945 0.3048)
			(end -0.67945 -0.305054)
			(stroke
				(width 0.1)
				(type default)
			)
			(layer "F.Fab")
		)
		(pad "1" smd circle
			(at -0.40005 0 90)
			(size 0 0)
			(layers "F.Cu" "F.Mask" "F.Paste")
			(net "FM_BIOS_POST_CMPLT_R_N")
		)
		(pad "2" smd circle
			(at 0.40005 0 90)
			(size 0 0)
			(layers "F.Cu" "F.Mask" "F.Paste")
			(net "FM_BIOS_POST_CMPLT_N")
		)
	)
	(footprint ""
		(layer "F.Cu")
		(at 167.900096 -160.50006)
		(property "Reference" "H89"
			(at -5.028184 -6.468618 0)
			(unlocked yes)
			(layer "F.SilkS")
			(effects
				(font
					(size 0.7874 0.5842)
					(thickness 0.1524)
				)
				(justify left)
			)
		)
		(property "Value" ""
			(at 0 0 0)
			(layer "F.Fab")
			(effects
				(font
					(size 1.27 1.27)
				)
			)
		)
		(duplicate_pad_numbers_are_jumpers no)
		(pad "1" thru_hole circle
			(at 0 0)
			(size 10.0076 10.0076)
			(drill 5.6134)
			(layers "*.Cu" "*.Mask")
			(remove_unused_layers no)
			(net "GND")
			(clearance -1.9431)
		)
	)
	(footprint ""
		(layer "F.Cu")
		(at 323.637148 -41.160954)
		(property "Reference" "R3681"
			(at 0 0 0)
			(layer "F.SilkS")
			(hide yes)
			(effects
				(font
					(size 1.27 1.27)
				)
			)
		)
		(property "Value" ""
			(at 0 0 0)
			(layer "F.Fab")
			(effects
				(font
					(size 1.27 1.27)
				)
			)
		)
		(duplicate_pad_numbers_are_jumpers no)
		(fp_line
			(start -0.7874 -0.4064)
			(end 0.7874 -0.4064)
			(stroke
				(width 0.1524)
				(type default)
			)
			(layer "F.SilkS")
		)
		(fp_line
			(start -0.7874 0.4064)
			(end -0.7874 -0.4064)
			(stroke
				(width 0.1524)
				(type default)
			)
			(layer "F.SilkS")
		)
		(fp_line
			(start 0.7874 -0.4064)
			(end 0.7874 0.4064)
			(stroke
				(width 0.1524)
				(type default)
			)
			(layer "F.SilkS")
		)
		(fp_line
			(start 0.7874 0.4064)
			(end -0.7874 0.4064)
			(stroke
				(width 0.1524)
				(type default)
			)
			(layer "F.SilkS")
		)
		(fp_line
			(start -0.67945 -0.305054)
			(end -0.12065 -0.305054)
			(stroke
				(width 0.1)
				(type default)
			)
			(layer "F.Fab")
		)
		(fp_line
			(start -0.67945 0.3048)
			(end -0.67945 -0.305054)
			(stroke
				(width 0.1)
				(type default)
			)
			(layer "F.Fab")
		)
		(fp_line
			(start -0.12065 -0.305054)
			(end -0.12065 -0.2794)
			(stroke
				(width 0.1)
				(type default)
			)
			(layer "F.Fab")
		)
		(fp_line
			(start -0.12065 -0.2794)
			(end 0.12065 -0.2794)
			(stroke
				(width 0.1)
				(type default)
			)
			(layer "F.Fab")
		)
		(fp_line
			(start -0.12065 0.2794)
			(end -0.12065 0.3048)
			(stroke
				(width 0.1)
				(type default)
			)
			(layer "F.Fab")
		)
		(fp_line
			(start -0.12065 0.3048)
			(end -0.67945 0.3048)
			(stroke
				(width 0.1)
				(type default)
			)
			(layer "F.Fab")
		)
		(fp_line
			(start 0.120396 0.2794)
			(end -0.12065 0.2794)
			(stroke
				(width 0.1)
				(type default)
			)
			(layer "F.Fab")
		)
		(fp_line
			(start 0.120396 0.3048)
			(end 0.120396 0.2794)
			(stroke
				(width 0.1)
				(type default)
			)
			(layer "F.Fab")
		)
		(fp_line
			(start 0.12065 -0.3048)
			(end 0.67945 -0.3048)
			(stroke
				(width 0.1)
				(type default)
			)
			(layer "F.Fab")
		)
		(fp_line
			(start 0.12065 -0.2794)
			(end 0.12065 -0.3048)
			(stroke
				(width 0.1)
				(type default)
			)
			(layer "F.Fab")
		)
		(fp_line
			(start 0.67945 -0.3048)
			(end 0.67945 0.3048)
			(stroke
				(width 0.1)
				(type default)
			)
			(layer "F.Fab")
		)
		(fp_line
			(start 0.67945 0.3048)
			(end 0.120396 0.3048)
			(stroke
				(width 0.1)
				(type default)
			)
			(layer "F.Fab")
		)
		(pad "1" smd rect
			(at -0.40005 0 180)
			(size 0.4572 0.508)
			(layers "F.Cu" "F.Mask" "F.Paste")
			(net "P3V3_AUX_ADC")
		)
		(pad "2" smd rect
			(at 0.40005 0 180)
			(size 0.4572 0.508)
			(layers "F.Cu" "F.Mask" "F.Paste")
			(net "P3V3_AUX_ADC_MAM")
		)
	)
	(footprint ""
		(layer "F.Cu")
		(at 328.868024 -140.245338)
		(property "Reference" "PC6005"
			(at 0 0 0)
			(layer "F.SilkS")
			(hide yes)
			(effects
				(font
					(size 1.27 1.27)
				)
			)
		)
		(property "Value" ""
			(at 0 0 0)
			(layer "F.Fab")
			(effects
				(font
					(size 1.27 1.27)
				)
			)
		)
		(duplicate_pad_numbers_are_jumpers no)
		(fp_line
			(start -0.7874 -0.4064)
			(end 0.7874 -0.4064)
			(stroke
				(width 0.1524)
				(type default)
			)
			(layer "F.SilkS")
		)
		(fp_line
			(start -0.7874 0.4064)
			(end -0.7874 -0.4064)
			(stroke
				(width 0.1524)
				(type default)
			)
			(layer "F.SilkS")
		)
		(fp_line
			(start 0.7874 -0.4064)
			(end 0.7874 0.4064)
			(stroke
				(width 0.1524)
				(type default)
			)
			(layer "F.SilkS")
		)
		(fp_line
			(start 0.7874 0.4064)
			(end -0.7874 0.4064)
			(stroke
				(width 0.1524)
				(type default)
			)
			(layer "F.SilkS")
		)
		(fp_line
			(start -0.67945 -0.305054)
			(end -0.12065 -0.305054)
			(stroke
				(width 0.1)
				(type default)
			)
			(layer "F.Fab")
		)
		(fp_line
			(start -0.67945 0.3048)
			(end -0.67945 -0.305054)
			(stroke
				(width 0.1)
				(type default)
			)
			(layer "F.Fab")
		)
		(fp_line
			(start -0.12065 -0.305054)
			(end -0.12065 -0.2794)
			(stroke
				(width 0.1)
				(type default)
			)
			(layer "F.Fab")
		)
		(fp_line
			(start -0.12065 -0.2794)
			(end 0.12065 -0.2794)
			(stroke
				(width 0.1)
				(type default)
			)
			(layer "F.Fab")
		)
		(fp_line
			(start -0.12065 0.2794)
			(end -0.12065 0.3048)
			(stroke
				(width 0.1)
				(type default)
			)
			(layer "F.Fab")
		)
		(fp_line
			(start -0.12065 0.3048)
			(end -0.67945 0.3048)
			(stroke
				(width 0.1)
				(type default)
			)
			(layer "F.Fab")
		)
		(fp_line
			(start 0.120396 0.2794)
			(end -0.12065 0.2794)
			(stroke
				(width 0.1)
				(type default)
			)
			(layer "F.Fab")
		)
		(fp_line
			(start 0.120396 0.3048)
			(end 0.120396 0.2794)
			(stroke
				(width 0.1)
				(type default)
			)
			(layer "F.Fab")
		)
		(fp_line
			(start 0.12065 -0.3048)
			(end 0.67945 -0.3048)
			(stroke
				(width 0.1)
				(type default)
			)
			(layer "F.Fab")
		)
		(fp_line
			(start 0.12065 -0.2794)
			(end 0.12065 -0.3048)
			(stroke
				(width 0.1)
				(type default)
			)
			(layer "F.Fab")
		)
		(fp_line
			(start 0.67945 -0.3048)
			(end 0.67945 0.3048)
			(stroke
				(width 0.1)
				(type default)
			)
			(layer "F.Fab")
		)
		(fp_line
			(start 0.67945 0.3048)
			(end 0.120396 0.3048)
			(stroke
				(width 0.1)
				(type default)
			)
			(layer "F.Fab")
		)
		(pad "1" smd circle
			(at -0.40005 0)
			(size 0 0)
			(layers "F.Cu" "F.Mask" "F.Paste")
			(net "PVDD18_S5_P0_FB_RC")
		)
		(pad "2" smd circle
			(at 0.40005 0)
			(size 0 0)
			(layers "F.Cu" "F.Mask" "F.Paste")
			(net "PVDD18_S5_P0_RGND")
		)
	)
	(footprint ""
		(layer "F.Cu")
		(at 200.939908 -106.513376 180)
		(property "Reference" "R228"
			(at 0 0 180)
			(layer "F.SilkS")
			(hide yes)
			(effects
				(font
					(size 1.27 1.27)
				)
			)
		)
		(property "Value" ""
			(at 0 0 180)
			(layer "F.Fab")
			(effects
				(font
					(size 1.27 1.27)
				)
			)
		)
		(duplicate_pad_numbers_are_jumpers no)
		(fp_line
			(start 0.7874 0.4064)
			(end -0.7874 0.4064)
			(stroke
				(width 0.1524)
				(type default)
			)
			(layer "F.SilkS")
		)
		(fp_line
			(start 0.7874 -0.4064)
			(end 0.7874 0.4064)
			(stroke
				(width 0.1524)
				(type default)
			)
			(layer "F.SilkS")
		)
		(fp_line
			(start -0.7874 0.4064)
			(end -0.7874 -0.4064)
			(stroke
				(width 0.1524)
				(type default)
			)
			(layer "F.SilkS")
		)
		(fp_line
			(start -0.7874 -0.4064)
			(end 0.7874 -0.4064)
			(stroke
				(width 0.1524)
				(type default)
			)
			(layer "F.SilkS")
		)
		(fp_line
			(start 0.67945 0.3048)
			(end 0.120396 0.3048)
			(stroke
				(width 0.1)
				(type default)
			)
			(layer "F.Fab")
		)
		(fp_line
			(start 0.67945 -0.3048)
			(end 0.67945 0.3048)
			(stroke
				(width 0.1)
				(type default)
			)
			(layer "F.Fab")
		)
		(fp_line
			(start 0.12065 -0.2794)
			(end 0.12065 -0.3048)
			(stroke
				(width 0.1)
				(type default)
			)
			(layer "F.Fab")
		)
		(fp_line
			(start 0.12065 -0.3048)
			(end 0.67945 -0.3048)
			(stroke
				(width 0.1)
				(type default)
			)
			(layer "F.Fab")
		)
		(fp_line
			(start 0.120396 0.3048)
			(end 0.120396 0.2794)
			(stroke
				(width 0.1)
				(type default)
			)
			(layer "F.Fab")
		)
		(fp_line
			(start 0.120396 0.2794)
			(end -0.12065 0.2794)
			(stroke
				(width 0.1)
				(type default)
			)
			(layer "F.Fab")
		)
		(fp_line
			(start -0.12065 0.3048)
			(end -0.67945 0.3048)
			(stroke
				(width 0.1)
				(type default)
			)
			(layer "F.Fab")
		)
		(fp_line
			(start -0.12065 0.2794)
			(end -0.12065 0.3048)
			(stroke
				(width 0.1)
				(type default)
			)
			(layer "F.Fab")
		)
		(fp_line
			(start -0.12065 -0.2794)
			(end 0.12065 -0.2794)
			(stroke
				(width 0.1)
				(type default)
			)
			(layer "F.Fab")
		)
		(fp_line
			(start -0.12065 -0.305054)
			(end -0.12065 -0.2794)
			(stroke
				(width 0.1)
				(type default)
			)
			(layer "F.Fab")
		)
		(fp_line
			(start -0.67945 0.3048)
			(end -0.67945 -0.305054)
			(stroke
				(width 0.1)
				(type default)
			)
			(layer "F.Fab")
		)
		(fp_line
			(start -0.67945 -0.305054)
			(end -0.12065 -0.305054)
			(stroke
				(width 0.1)
				(type default)
			)
			(layer "F.Fab")
		)
		(pad "1" smd circle
			(at -0.40005 0 180)
			(size 0 0)
			(layers "F.Cu" "F.Mask" "F.Paste")
			(net "PWRGD_PVDD11_S3_P0")
		)
		(pad "2" smd circle
			(at 0.40005 0 180)
			(size 0 0)
			(layers "F.Cu" "F.Mask" "F.Paste")
			(net "FM_PWRGD_PVDD11_S3_P0")
		)
	)
	(footprint ""
		(layer "F.Cu")
		(at 188.552582 -356.178358 90)
		(property "Reference" "PC504_2"
			(at 0 0 90)
			(layer "F.SilkS")
			(hide yes)
			(effects
				(font
					(size 1.27 1.27)
				)
			)
		)
		(property "Value" ""
			(at 0 0 90)
			(layer "F.Fab")
			(effects
				(font
					(size 1.27 1.27)
				)
			)
		)
		(duplicate_pad_numbers_are_jumpers no)
		(fp_line
			(start 0.7874 -0.4064)
			(end 0.7874 0.4064)
			(stroke
				(width 0.1524)
				(type default)
			)
			(layer "F.SilkS")
		)
		(fp_line
			(start -0.7874 -0.4064)
			(end 0.7874 -0.4064)
			(stroke
				(width 0.1524)
				(type default)
			)
			(layer "F.SilkS")
		)
		(fp_line
			(start 0.7874 0.4064)
			(end -0.7874 0.4064)
			(stroke
				(width 0.1524)
				(type default)
			)
			(layer "F.SilkS")
		)
		(fp_line
			(start -0.7874 0.4064)
			(end -0.7874 -0.4064)
			(stroke
				(width 0.1524)
				(type default)
			)
			(layer "F.SilkS")
		)
		(fp_line
			(start -0.12065 -0.305054)
			(end -0.12065 -0.2794)
			(stroke
				(width 0.1)
				(type default)
			)
			(layer "F.Fab")
		)
		(fp_line
			(start -0.67945 -0.305054)
			(end -0.12065 -0.305054)
			(stroke
				(width 0.1)
				(type default)
			)
			(layer "F.Fab")
		)
		(fp_line
			(start 0.67945 -0.3048)
			(end 0.67945 0.3048)
			(stroke
				(width 0.1)
				(type default)
			)
			(layer "F.Fab")
		)
		(fp_line
			(start 0.12065 -0.3048)
			(end 0.67945 -0.3048)
			(stroke
				(width 0.1)
				(type default)
			)
			(layer "F.Fab")
		)
		(fp_line
			(start 0.12065 -0.2794)
			(end 0.12065 -0.3048)
			(stroke
				(width 0.1)
				(type default)
			)
			(layer "F.Fab")
		)
		(fp_line
			(start -0.12065 -0.2794)
			(end 0.12065 -0.2794)
			(stroke
				(width 0.1)
				(type default)
			)
			(layer "F.Fab")
		)
		(fp_line
			(start 0.120396 0.2794)
			(end -0.12065 0.2794)
			(stroke
				(width 0.1)
				(type default)
			)
			(layer "F.Fab")
		)
		(fp_line
			(start -0.12065 0.2794)
			(end -0.12065 0.3048)
			(stroke
				(width 0.1)
				(type default)
			)
			(layer "F.Fab")
		)
		(fp_line
			(start 0.67945 0.3048)
			(end 0.120396 0.3048)
			(stroke
				(width 0.1)
				(type default)
			)
			(layer "F.Fab")
		)
		(fp_line
			(start 0.120396 0.3048)
			(end 0.120396 0.2794)
			(stroke
				(width 0.1)
				(type default)
			)
			(layer "F.Fab")
		)
		(fp_line
			(start -0.12065 0.3048)
			(end -0.67945 0.3048)
			(stroke
				(width 0.1)
				(type default)
			)
			(layer "F.Fab")
		)
		(fp_line
			(start -0.67945 0.3048)
			(end -0.67945 -0.305054)
			(stroke
				(width 0.1)
				(type default)
			)
			(layer "F.Fab")
		)
		(pad "1" smd circle
			(at -0.40005 0 90)
			(size 0 0)
			(layers "F.Cu" "F.Mask" "F.Paste")
			(net "PVDD11_S3_P1_VCCS")
		)
		(pad "2" smd circle
			(at 0.40005 0 90)
			(size 0 0)
			(layers "F.Cu" "F.Mask" "F.Paste")
			(net "GND")
		)
	)
	(footprint ""
		(layer "F.Cu")
		(at 153.277824 -191.358266 -90)
		(property "Reference" "R3354"
			(at 0 0 270)
			(layer "F.SilkS")
			(hide yes)
			(effects
				(font
					(size 1.27 1.27)
				)
			)
		)
		(property "Value" ""
			(at 0 0 270)
			(layer "F.Fab")
			(effects
				(font
					(size 1.27 1.27)
				)
			)
		)
		(duplicate_pad_numbers_are_jumpers no)
		(fp_line
			(start -0.7874 0.4064)
			(end -0.7874 -0.061976)
			(stroke
				(width 0.1524)
				(type default)
			)
			(layer "F.SilkS")
		)
		(fp_line
			(start 0.7874 0.4064)
			(end -0.7874 0.4064)
			(stroke
				(width 0.1524)
				(type default)
			)
			(layer "F.SilkS")
		)
		(fp_line
			(start 0.7874 -0.061976)
			(end 0.7874 0.4064)
			(stroke
				(width 0.1524)
				(type default)
			)
			(layer "F.SilkS")
		)
		(fp_line
			(start -0.386334 -0.4064)
			(end 0.324866 -0.4064)
			(stroke
				(width 0.1524)
				(type default)
			)
			(layer "F.SilkS")
		)
		(fp_line
			(start -0.67945 0.3048)
			(end -0.67945 -0.305054)
			(stroke
				(width 0.1)
				(type default)
			)
			(layer "F.Fab")
		)
		(fp_line
			(start -0.12065 0.3048)
			(end -0.67945 0.3048)
			(stroke
				(width 0.1)
				(type default)
			)
			(layer "F.Fab")
		)
		(fp_line
			(start 0.120396 0.3048)
			(end 0.120396 0.2794)
			(stroke
				(width 0.1)
				(type default)
			)
			(layer "F.Fab")
		)
		(fp_line
			(start 0.67945 0.3048)
			(end 0.120396 0.3048)
			(stroke
				(width 0.1)
				(type default)
			)
			(layer "F.Fab")
		)
		(fp_line
			(start -0.12065 0.2794)
			(end -0.12065 0.3048)
			(stroke
				(width 0.1)
				(type default)
			)
			(layer "F.Fab")
		)
		(fp_line
			(start 0.120396 0.2794)
			(end -0.12065 0.2794)
			(stroke
				(width 0.1)
				(type default)
			)
			(layer "F.Fab")
		)
		(fp_line
			(start -0.12065 -0.2794)
			(end 0.12065 -0.2794)
			(stroke
				(width 0.1)
				(type default)
			)
			(layer "F.Fab")
		)
		(fp_line
			(start 0.12065 -0.2794)
			(end 0.12065 -0.3048)
			(stroke
				(width 0.1)
				(type default)
			)
			(layer "F.Fab")
		)
		(fp_line
			(start 0.12065 -0.3048)
			(end 0.67945 -0.3048)
			(stroke
				(width 0.1)
				(type default)
			)
			(layer "F.Fab")
		)
		(fp_line
			(start 0.67945 -0.3048)
			(end 0.67945 0.3048)
			(stroke
				(width 0.1)
				(type default)
			)
			(layer "F.Fab")
		)
		(fp_line
			(start -0.67945 -0.305054)
			(end -0.12065 -0.305054)
			(stroke
				(width 0.1)
				(type default)
			)
			(layer "F.Fab")
		)
		(fp_line
			(start -0.12065 -0.305054)
			(end -0.12065 -0.2794)
			(stroke
				(width 0.1)
				(type default)
			)
			(layer "F.Fab")
		)
		(pad "1" smd circle
			(at -0.40005 0 270)
			(size 0 0)
			(layers "F.Cu" "F.Mask" "F.Paste")
			(net "CLK_100M_CPU1_CLK01_R_DP")
		)
		(pad "2" smd circle
			(at 0.40005 0 270)
			(size 0 0)
			(layers "F.Cu" "F.Mask" "F.Paste")
			(net "CLK_100M_CPU1_CLK01_DP")
		)
	)
)
